(kicad_pcb
	(version 20260206)
	(generator "pcbnew")
	(generator_version "10.0")
	(general
		(thickness 1.6)
		(legacy_teardrops no)
	)
	(paper "A4")
	(title_block
		(title "Bryce Canyon_SCC_16316-1_OCP.brd")
		(comment 1 "Bryce Canyon / footprints 45-53 of 1561")
	)
	(layers
		(0 "F.Cu" signal "TOP")
		(4 "In1.Cu" signal "L2GND")
		(6 "In2.Cu" signal "L3")
		(8 "In3.Cu" signal "L4VCC")
		(10 "In4.Cu" signal "L5VCC")
		(12 "In5.Cu" signal "L6")
		(14 "In6.Cu" signal "L7GND")
		(2 "B.Cu" signal "BOTTOM")
		(9 "F.Adhes" user "F.Adhesive")
		(11 "B.Adhes" user "B.Adhesive")
		(13 "F.Paste" user "Package Geometry/Pastemask Top")
		(15 "B.Paste" user "Package Geometry/Pastemask Bottom")
		(5 "F.SilkS" user "Ref Des/Silkscreen Top")
		(7 "B.SilkS" user "Ref Des/Silkscreen Bottom")
		(1 "F.Mask" user "Board Geometry/Soldermask Top")
		(3 "B.Mask" user "Board Geometry/Soldermask Bottom")
		(17 "Dwgs.User" user "User.Drawings")
		(19 "Cmts.User" user "User.Comments")
		(21 "Eco1.User" user "User.Eco1")
		(23 "Eco2.User" user "User.Eco2")
		(25 "Edge.Cuts" user "Board Geometry/Outline")
		(27 "Margin" user)
		(31 "F.CrtYd" user "Package Geometry/Place Bound Top")
		(29 "B.CrtYd" user "Package Geometry/Place Bound Bottom")
		(35 "F.Fab" user "Ref Des/Assembly Top")
		(33 "B.Fab" user "Ref Des/Assembly Bottom")
	)
	(footprint ""
		(layer "F.Cu")
		(at 159.2326 -111.0996)
		(property "Reference" "C698"
			(at 0 0 0)
			(layer "F.SilkS")
			(hide yes)
			(effects
				(font
					(size 1.27 1.27)
				)
			)
		)
		(property "Value" "SC10U16V5KX-7-GP-U"
			(at -0.0762 -6.1214 0)
			(unlocked yes)
			(layer "F.Fab")
			(hide yes)
			(effects
				(font
					(size 1.016 1.016)
					(thickness 0.1524)
				)
			)
		)
		(property "Device Type" "C805H58"
			(at -0.0762 -8.1534 0)
			(unlocked yes)
			(layer "F.Fab")
			(hide yes)
			(effects
				(font
					(size 1.016 1.016)
					(thickness 0.1524)
				)
			)
		)
		(duplicate_pad_numbers_are_jumpers no)
		(fp_line
			(start 0.635 0)
			(end -0.635 0)
			(stroke
				(width 0.508)
				(type default)
			)
			(layer "F.SilkS")
		)
		(fp_rect
			(start -0.9652 1.778)
			(end 0.9652 -1.778)
			(stroke
				(width 0)
				(type default)
			)
			(fill no)
			(layer "F.CrtYd")
		)
		(fp_poly
			(pts
				(xy -0.9652 -1.778) (xy 0.9652 -1.778) (xy 0.9652 1.778) (xy -0.9652 1.778)
			)
			(stroke
				(width 0)
				(type default)
			)
			(fill no)
			(layer "F.Fab")
		)
		(pad "1" smd rect
			(at 0 -0.9652)
			(size 1.397 1.143)
			(layers "F.Cu" "F.Mask" "F.Paste")
			(net "P12V_STBY_VIN_U11")
		)
		(pad "2" smd rect
			(at 0 0.9652)
			(size 1.397 1.143)
			(layers "F.Cu" "F.Mask" "F.Paste")
			(net "GND")
		)
	)
	(footprint ""
		(layer "F.Cu")
		(at 131.572 -89.7001)
		(property "Reference" "R119"
			(at 0 0 0)
			(layer "F.SilkS")
			(hide yes)
			(effects
				(font
					(size 1.27 1.27)
				)
			)
		)
		(property "Value" "4K75R2F-1-GP"
			(at 0.064008 -3.993896 0)
			(unlocked yes)
			(layer "F.Fab")
			(hide yes)
			(effects
				(font
					(size 1.016 1.016)
					(thickness 0.1524)
				)
			)
		)
		(property "Device Type" "R402H16"
			(at 0.064008 -5.517896 0)
			(unlocked yes)
			(layer "F.Fab")
			(hide yes)
			(effects
				(font
					(size 1.016 1.016)
					(thickness 0.1524)
				)
			)
		)
		(duplicate_pad_numbers_are_jumpers no)
		(fp_line
			(start -0.508 -0.9398)
			(end -0.508 0.9398)
			(stroke
				(width 0.1524)
				(type default)
			)
			(layer "F.SilkS")
		)
		(fp_line
			(start 0.508 -0.9398)
			(end -0.508 -0.9398)
			(stroke
				(width 0.1524)
				(type default)
			)
			(layer "F.SilkS")
		)
		(fp_rect
			(start -0.508 0.9398)
			(end 0.508 -0.9398)
			(stroke
				(width 0)
				(type default)
			)
			(fill no)
			(layer "F.CrtYd")
		)
		(fp_rect
			(start -0.508 0.9398)
			(end 0.508 -0.9398)
			(stroke
				(width 0)
				(type default)
			)
			(fill no)
			(layer "F.Fab")
		)
		(pad "1" smd custom
			(at 0 -0.4445)
			(size 0.1397 0.1397)
			(layers "F.Cu" "F.Mask" "F.Paste")
			(net "P1V8_E")
			(options
				(clearance outline)
				(anchor circle)
			)
			(primitives
				(gr_poly
					(pts
						(arc
							(start -0.1778 -0.2794)
							(mid -0.249642 -0.249642)
							(end -0.2794 -0.1778)
						)
						(arc
							(start -0.2794 0.1778)
							(mid -0.249642 0.249642)
							(end -0.1778 0.2794)
						)
						(arc
							(start 0.1778 0.2794)
							(mid 0.249642 0.249642)
							(end 0.2794 0.1778)
						)
						(arc
							(start 0.2794 -0.1778)
							(mid 0.249642 -0.249642)
							(end 0.1778 -0.2794)
						)
					)
					(width 0)
					(fill yes)
				)
			)
		)
		(pad "2" smd custom
			(at 0 0.4445)
			(size 0.1397 0.1397)
			(layers "F.Cu" "F.Mask" "F.Paste")
			(net "UART_CTS")
			(options
				(clearance outline)
				(anchor circle)
			)
			(primitives
				(gr_poly
					(pts
						(arc
							(start -0.1778 -0.2794)
							(mid -0.249642 -0.249642)
							(end -0.2794 -0.1778)
						)
						(arc
							(start -0.2794 0.1778)
							(mid -0.249642 0.249642)
							(end -0.1778 0.2794)
						)
						(arc
							(start 0.1778 0.2794)
							(mid 0.249642 0.249642)
							(end 0.2794 0.1778)
						)
						(arc
							(start 0.2794 -0.1778)
							(mid 0.249642 -0.249642)
							(end 0.1778 -0.2794)
						)
					)
					(width 0)
					(fill yes)
				)
			)
		)
	)
	(footprint ""
		(layer "F.Cu")
		(at 70.485 -50.292 90)
		(property "Reference" "L13"
			(at 0 0 90)
			(layer "F.SilkS")
			(hide yes)
			(effects
				(font
					(size 1.27 1.27)
				)
			)
		)
		(property "Value" "MPZ2012S300AT-GP"
			(at 0 -4.2418 90)
			(unlocked yes)
			(layer "F.Fab")
			(hide yes)
			(effects
				(font
					(size 1.016 1.016)
					(thickness 0.1524)
				)
			)
		)
		(property "Device Type" "L805H42"
			(at 0 -5.7912 90)
			(unlocked yes)
			(layer "F.Fab")
			(hide yes)
			(effects
				(font
					(size 1.016 1.016)
					(thickness 0.1524)
				)
			)
		)
		(duplicate_pad_numbers_are_jumpers no)
		(fp_line
			(start 0.889 -1.7018)
			(end 0.889 1.7018)
			(stroke
				(width 0.1524)
				(type default)
			)
			(layer "F.SilkS")
		)
		(fp_line
			(start -0.889 -1.7018)
			(end 0.889 -1.7018)
			(stroke
				(width 0.1524)
				(type default)
			)
			(layer "F.SilkS")
		)
		(fp_line
			(start 0.889 1.7018)
			(end -0.889 1.7018)
			(stroke
				(width 0.1524)
				(type default)
			)
			(layer "F.SilkS")
		)
		(fp_line
			(start -0.889 1.7018)
			(end -0.889 -1.7018)
			(stroke
				(width 0.1524)
				(type default)
			)
			(layer "F.SilkS")
		)
		(fp_rect
			(start -0.9652 1.778)
			(end 0.9652 -1.778)
			(stroke
				(width 0)
				(type default)
			)
			(fill no)
			(layer "F.CrtYd")
		)
		(fp_rect
			(start -0.9652 1.778)
			(end 0.9652 -1.778)
			(stroke
				(width 0)
				(type default)
			)
			(fill no)
			(layer "F.Fab")
		)
		(pad "1" smd rect
			(at 0 -0.9652 90)
			(size 1.397 1.143)
			(layers "F.Cu" "F.Mask" "F.Paste")
			(net "P0V9")
		)
		(pad "2" smd rect
			(at 0 0.9652 90)
			(size 1.397 1.143)
			(layers "F.Cu" "F.Mask" "F.Paste")
			(net "GB_VDDA")
		)
	)
	(footprint ""
		(layer "F.Cu")
		(at 61.654182 -17.401794)
		(property "Reference" "C743"
			(at 0 0 0)
			(layer "F.SilkS")
			(hide yes)
			(effects
				(font
					(size 1.27 1.27)
				)
			)
		)
		(property "Value" "SCD1U16V2KX-3GP"
			(at 1.1811 -2.7051 0)
			(unlocked yes)
			(layer "F.Fab")
			(hide yes)
			(effects
				(font
					(size 1.016 1.016)
					(thickness 0.1524)
				)
			)
		)
		(property "Device Type" "C402H22"
			(at 1.1811 -4.2291 0)
			(unlocked yes)
			(layer "F.Fab")
			(hide yes)
			(effects
				(font
					(size 1.016 1.016)
					(thickness 0.1524)
				)
			)
		)
		(duplicate_pad_numbers_are_jumpers no)
		(fp_rect
			(start -0.4318 0.9525)
			(end 0.4318 -0.9525)
			(stroke
				(width 0)
				(type default)
			)
			(fill no)
			(layer "F.CrtYd")
		)
		(fp_rect
			(start -0.4318 0.9525)
			(end 0.4318 -0.9525)
			(stroke
				(width 0)
				(type default)
			)
			(fill no)
			(layer "F.Fab")
		)
		(pad "1" smd custom
			(at 0 -0.4445)
			(size 0.1524 0.1524)
			(layers "F.Cu" "F.Mask" "F.Paste")
			(net "U49_OE")
			(options
				(clearance outline)
				(anchor circle)
			)
			(primitives
				(gr_poly
					(pts
						(arc
							(start 0.3048 -0.2032)
							(mid 0.275042 -0.275042)
							(end 0.2032 -0.3048)
						)
						(arc
							(start -0.2032 -0.3048)
							(mid -0.275042 -0.275042)
							(end -0.3048 -0.2032)
						)
						(arc
							(start -0.3048 0.2032)
							(mid -0.275042 0.275042)
							(end -0.2032 0.3048)
						)
						(arc
							(start 0.2032 0.3048)
							(mid 0.275042 0.275042)
							(end 0.3048 0.2032)
						)
					)
					(width 0)
					(fill yes)
				)
			)
		)
		(pad "2" smd custom
			(at 0 0.4445)
			(size 0.1524 0.1524)
			(layers "F.Cu" "F.Mask" "F.Paste")
			(net "GND")
			(options
				(clearance outline)
				(anchor circle)
			)
			(primitives
				(gr_poly
					(pts
						(arc
							(start 0.3048 -0.2032)
							(mid 0.275042 -0.275042)
							(end 0.2032 -0.3048)
						)
						(arc
							(start -0.2032 -0.3048)
							(mid -0.275042 -0.275042)
							(end -0.3048 -0.2032)
						)
						(arc
							(start -0.3048 0.2032)
							(mid -0.275042 0.275042)
							(end -0.2032 0.3048)
						)
						(arc
							(start 0.2032 0.3048)
							(mid 0.275042 0.275042)
							(end 0.3048 0.2032)
						)
					)
					(width 0)
					(fill yes)
				)
			)
		)
	)
	(footprint ""
		(layer "F.Cu")
		(at 194.1322 -41.7068 90)
		(property "Reference" "R171"
			(at 0 0 90)
			(layer "F.SilkS")
			(hide yes)
			(effects
				(font
					(size 1.27 1.27)
				)
			)
		)
		(property "Value" "10KR2F-2-GP"
			(at 0.064008 -3.993896 90)
			(unlocked yes)
			(layer "F.Fab")
			(hide yes)
			(effects
				(font
					(size 1.016 1.016)
					(thickness 0.1524)
				)
			)
		)
		(property "Device Type" "R402H16"
			(at 0.064008 -5.517896 90)
			(unlocked yes)
			(layer "F.Fab")
			(hide yes)
			(effects
				(font
					(size 1.016 1.016)
					(thickness 0.1524)
				)
			)
		)
		(duplicate_pad_numbers_are_jumpers no)
		(fp_line
			(start 0.508 -0.9398)
			(end -0.508 -0.9398)
			(stroke
				(width 0.1524)
				(type default)
			)
			(layer "F.SilkS")
		)
		(fp_line
			(start -0.508 -0.9398)
			(end -0.508 0.9398)
			(stroke
				(width 0.1524)
				(type default)
			)
			(layer "F.SilkS")
		)
		(fp_rect
			(start -0.508 0.9398)
			(end 0.508 -0.9398)
			(stroke
				(width 0)
				(type default)
			)
			(fill no)
			(layer "F.CrtYd")
		)
		(fp_rect
			(start -0.508 0.9398)
			(end 0.508 -0.9398)
			(stroke
				(width 0)
				(type default)
			)
			(fill no)
			(layer "F.Fab")
		)
		(pad "1" smd custom
			(at 0 -0.4445 90)
			(size 0.1397 0.1397)
			(layers "F.Cu" "F.Mask" "F.Paste")
			(net "IOC_CLK_SEL0")
			(options
				(clearance outline)
				(anchor circle)
			)
			(primitives
				(gr_poly
					(pts
						(arc
							(start -0.1778 -0.2794)
							(mid -0.249642 -0.249642)
							(end -0.2794 -0.1778)
						)
						(arc
							(start -0.2794 0.1778)
							(mid -0.249642 0.249642)
							(end -0.1778 0.2794)
						)
						(arc
							(start 0.1778 0.2794)
							(mid 0.249642 0.249642)
							(end 0.2794 0.1778)
						)
						(arc
							(start 0.2794 -0.1778)
							(mid 0.249642 -0.249642)
							(end 0.1778 -0.2794)
						)
					)
					(width 0)
					(fill yes)
				)
			)
		)
		(pad "2" smd custom
			(at 0 0.4445 90)
			(size 0.1397 0.1397)
			(layers "F.Cu" "F.Mask" "F.Paste")
			(net "P1V8_C")
			(options
				(clearance outline)
				(anchor circle)
			)
			(primitives
				(gr_poly
					(pts
						(arc
							(start -0.1778 -0.2794)
							(mid -0.249642 -0.249642)
							(end -0.2794 -0.1778)
						)
						(arc
							(start -0.2794 0.1778)
							(mid -0.249642 0.249642)
							(end -0.1778 0.2794)
						)
						(arc
							(start 0.1778 0.2794)
							(mid 0.249642 0.249642)
							(end 0.2794 0.1778)
						)
						(arc
							(start 0.2794 -0.1778)
							(mid 0.249642 -0.249642)
							(end 0.1778 -0.2794)
						)
					)
					(width 0)
					(fill yes)
				)
			)
		)
	)
	(footprint ""
		(layer "F.Cu")
		(at 124.6632 -109.93628)
		(property "Reference" "TP152"
			(at 0 0 0)
			(layer "F.SilkS")
			(hide yes)
			(effects
				(font
					(size 1.27 1.27)
				)
			)
		)
		(property "Value" "TPAD28-2-GP"
			(at -0.0127 -1.6637 0)
			(unlocked yes)
			(layer "F.Fab")
			(hide yes)
			(effects
				(font
					(size 1.016 1.016)
					(thickness 0.1524)
				)
			)
		)
		(property "Device Type" "TPAD28"
			(at -0.0127 -3.1877 0)
			(unlocked yes)
			(layer "F.Fab")
			(hide yes)
			(effects
				(font
					(size 1.016 1.016)
					(thickness 0.1524)
				)
			)
		)
		(duplicate_pad_numbers_are_jumpers no)
		(fp_poly
			(pts
				(arc
					(start 0.3556 0)
					(mid -0.3556 0)
					(end 0.3556 0)
				)
			)
			(stroke
				(width 0)
				(type default)
			)
			(fill no)
			(layer "F.CrtYd")
		)
		(fp_poly
			(pts
				(arc
					(start 0.6096 0)
					(mid -0.6096 0)
					(end 0.6096 0)
				)
			)
			(stroke
				(width 0)
				(type default)
			)
			(fill no)
			(layer "F.Fab")
		)
		(pad "1" smd circle
			(at 0 0)
			(size 0.7112 0.7112)
			(layers "F.Cu" "F.Mask" "F.Paste")
			(net "INT_C2_CONN1")
		)
	)
	(footprint ""
		(layer "F.Cu")
		(at 160.274 -83.224116 90)
		(property "Reference" "C526"
			(at 0 0 90)
			(layer "F.SilkS")
			(hide yes)
			(effects
				(font
					(size 1.27 1.27)
				)
			)
		)
		(property "Value" "SCD1U16V2KX-3GP"
			(at 1.1811 -2.7051 90)
			(unlocked yes)
			(layer "F.Fab")
			(hide yes)
			(effects
				(font
					(size 1.016 1.016)
					(thickness 0.1524)
				)
			)
		)
		(property "Device Type" "C402H22"
			(at 1.1811 -4.2291 90)
			(unlocked yes)
			(layer "F.Fab")
			(hide yes)
			(effects
				(font
					(size 1.016 1.016)
					(thickness 0.1524)
				)
			)
		)
		(duplicate_pad_numbers_are_jumpers no)
		(fp_rect
			(start -0.4318 0.9525)
			(end 0.4318 -0.9525)
			(stroke
				(width 0)
				(type default)
			)
			(fill no)
			(layer "F.CrtYd")
		)
		(fp_rect
			(start -0.4318 0.9525)
			(end 0.4318 -0.9525)
			(stroke
				(width 0)
				(type default)
			)
			(fill no)
			(layer "F.Fab")
		)
		(pad "1" smd custom
			(at 0 -0.4445 90)
			(size 0.1524 0.1524)
			(layers "F.Cu" "F.Mask" "F.Paste")
			(net "P0V9_SENSE")
			(options
				(clearance outline)
				(anchor circle)
			)
			(primitives
				(gr_poly
					(pts
						(arc
							(start 0.3048 -0.2032)
							(mid 0.275042 -0.275042)
							(end 0.2032 -0.3048)
						)
						(arc
							(start -0.2032 -0.3048)
							(mid -0.275042 -0.275042)
							(end -0.3048 -0.2032)
						)
						(arc
							(start -0.3048 0.2032)
							(mid -0.275042 0.275042)
							(end -0.2032 0.3048)
						)
						(arc
							(start 0.2032 0.3048)
							(mid 0.275042 0.275042)
							(end 0.3048 0.2032)
						)
					)
					(width 0)
					(fill yes)
				)
			)
		)
		(pad "2" smd custom
			(at 0 0.4445 90)
			(size 0.1524 0.1524)
			(layers "F.Cu" "F.Mask" "F.Paste")
			(net "GND")
			(options
				(clearance outline)
				(anchor circle)
			)
			(primitives
				(gr_poly
					(pts
						(arc
							(start 0.3048 -0.2032)
							(mid 0.275042 -0.275042)
							(end 0.2032 -0.3048)
						)
						(arc
							(start -0.2032 -0.3048)
							(mid -0.275042 -0.275042)
							(end -0.3048 -0.2032)
						)
						(arc
							(start -0.3048 0.2032)
							(mid -0.275042 0.275042)
							(end -0.2032 0.3048)
						)
						(arc
							(start 0.2032 0.3048)
							(mid 0.275042 0.275042)
							(end 0.3048 0.2032)
						)
					)
					(width 0)
					(fill yes)
				)
			)
		)
	)
	(footprint ""
		(layer "F.Cu")
		(at 165.461442 -82.200496 90)
		(property "Reference" "C635"
			(at 0 0 90)
			(layer "F.SilkS")
			(hide yes)
			(effects
				(font
					(size 1.27 1.27)
				)
			)
		)
		(property "Value" "SC10U16V5KX-7-GP-U"
			(at -0.0762 -6.1214 90)
			(unlocked yes)
			(layer "F.Fab")
			(hide yes)
			(effects
				(font
					(size 1.016 1.016)
					(thickness 0.1524)
				)
			)
		)
		(property "Device Type" "C805H58"
			(at -0.0762 -8.1534 90)
			(unlocked yes)
			(layer "F.Fab")
			(hide yes)
			(effects
				(font
					(size 1.016 1.016)
					(thickness 0.1524)
				)
			)
		)
		(duplicate_pad_numbers_are_jumpers no)
		(fp_line
			(start 0.635 0)
			(end -0.635 0)
			(stroke
				(width 0.508)
				(type default)
			)
			(layer "F.SilkS")
		)
		(fp_rect
			(start -0.9652 1.778)
			(end 0.9652 -1.778)
			(stroke
				(width 0)
				(type default)
			)
			(fill no)
			(layer "F.CrtYd")
		)
		(fp_poly
			(pts
				(xy -0.9652 -1.778) (xy 0.9652 -1.778) (xy 0.9652 1.778) (xy -0.9652 1.778)
			)
			(stroke
				(width 0)
				(type default)
			)
			(fill no)
			(layer "F.Fab")
		)
		(pad "1" smd rect
			(at 0 -0.9652 90)
			(size 1.397 1.143)
			(layers "F.Cu" "F.Mask" "F.Paste")
			(net "P12V_SYBY_VDD_U6")
		)
		(pad "2" smd rect
			(at 0 0.9652 90)
			(size 1.397 1.143)
			(layers "F.Cu" "F.Mask" "F.Paste")
			(net "GND")
		)
	)
	(footprint ""
		(layer "F.Cu")
		(at 151.257 -84.9249 -90)
		(property "Reference" "C524"
			(at 0 0 270)
			(layer "F.SilkS")
			(hide yes)
			(effects
				(font
					(size 1.27 1.27)
				)
			)
		)
		(property "Value" "SCD1U16V2KX-3GP"
			(at 1.1811 -2.7051 270)
			(unlocked yes)
			(layer "F.Fab")
			(hide yes)
			(effects
				(font
					(size 1.016 1.016)
					(thickness 0.1524)
				)
			)
		)
		(property "Device Type" "C402H22"
			(at 1.1811 -4.2291 270)
			(unlocked yes)
			(layer "F.Fab")
			(hide yes)
			(effects
				(font
					(size 1.016 1.016)
					(thickness 0.1524)
				)
			)
		)
		(duplicate_pad_numbers_are_jumpers no)
		(fp_rect
			(start -0.4318 0.9525)
			(end 0.4318 -0.9525)
			(stroke
				(width 0)
				(type default)
			)
			(fill no)
			(layer "F.CrtYd")
		)
		(fp_rect
			(start -0.4318 0.9525)
			(end 0.4318 -0.9525)
			(stroke
				(width 0)
				(type default)
			)
			(fill no)
			(layer "F.Fab")
		)
		(pad "1" smd custom
			(at 0 -0.4445 270)
			(size 0.1524 0.1524)
			(layers "F.Cu" "F.Mask" "F.Paste")
			(net "P1V8_E_SENSE")
			(options
				(clearance outline)
				(anchor circle)
			)
			(primitives
				(gr_poly
					(pts
						(arc
							(start 0.3048 -0.2032)
							(mid 0.275042 -0.275042)
							(end 0.2032 -0.3048)
						)
						(arc
							(start -0.2032 -0.3048)
							(mid -0.275042 -0.275042)
							(end -0.3048 -0.2032)
						)
						(arc
							(start -0.3048 0.2032)
							(mid -0.275042 0.275042)
							(end -0.2032 0.3048)
						)
						(arc
							(start 0.2032 0.3048)
							(mid 0.275042 0.275042)
							(end 0.3048 0.2032)
						)
					)
					(width 0)
					(fill yes)
				)
			)
		)
		(pad "2" smd custom
			(at 0 0.4445 270)
			(size 0.1524 0.1524)
			(layers "F.Cu" "F.Mask" "F.Paste")
			(net "GND")
			(options
				(clearance outline)
				(anchor circle)
			)
			(primitives
				(gr_poly
					(pts
						(arc
							(start 0.3048 -0.2032)
							(mid 0.275042 -0.275042)
							(end 0.2032 -0.3048)
						)
						(arc
							(start -0.2032 -0.3048)
							(mid -0.275042 -0.275042)
							(end -0.3048 -0.2032)
						)
						(arc
							(start -0.3048 0.2032)
							(mid -0.275042 0.275042)
							(end -0.2032 0.3048)
						)
						(arc
							(start 0.2032 0.3048)
							(mid 0.275042 0.275042)
							(end 0.3048 0.2032)
						)
					)
					(width 0)
					(fill yes)
				)
			)
		)
	)
)
